(kicad_pcb
	(version 20260206)
	(generator "pcbnew")
	(generator_version "10.0")
	(general
		(thickness 1.6)
		(legacy_teardrops no)
	)
	(paper "A4")
	(title_block
		(title "12092022_DA0F0TMDCD0_F0T_Management_Board_D_brd_V3_OCP.brd")
		(comment 1 "Grand Teton / footprints 257-262 of 1440")
	)
	(layers
		(0 "F.Cu" signal "TOP")
		(4 "In1.Cu" signal "GND")
		(6 "In2.Cu" signal "IN1")
		(8 "In3.Cu" signal "GND1")
		(10 "In4.Cu" signal "IN2")
		(12 "In5.Cu" signal "VCC")
		(14 "In6.Cu" signal "VCC1")
		(16 "In7.Cu" signal "IN3")
		(18 "In8.Cu" signal "GND2")
		(20 "In9.Cu" signal "IN4")
		(22 "In10.Cu" signal "GND3")
		(2 "B.Cu" signal "BOTTOM")
		(9 "F.Adhes" user "F.Adhesive")
		(11 "B.Adhes" user "B.Adhesive")
		(13 "F.Paste" user "Package Geometry/Pastemask Top")
		(15 "B.Paste" user "Package Geometry/Pastemask Bottom")
		(5 "F.SilkS" user "Ref Des/Silkscreen Top")
		(7 "B.SilkS" user "Ref Des/Silkscreen Bottom")
		(1 "F.Mask" user "Board Geometry/Soldermask Top")
		(3 "B.Mask" user "Board Geometry/Soldermask Bottom")
		(17 "Dwgs.User" user "User.Drawings")
		(19 "Cmts.User" user "User.Comments")
		(21 "Eco1.User" user "User.Eco1")
		(23 "Eco2.User" user "User.Eco2")
		(25 "Edge.Cuts" user "Board Geometry/Outline")
		(27 "Margin" user)
		(31 "F.CrtYd" user "Package Geometry/Place Bound Top")
		(29 "B.CrtYd" user "Package Geometry/Place Bound Bottom")
		(35 "F.Fab" user "Ref Des/Assembly Top")
		(33 "B.Fab" user "Ref Des/Assembly Bottom")
	)
	(footprint ""
		(layer "F.Cu")
		(at 39.8272 -76.454)
		(property "Reference" "R550"
			(at 0 0 0)
			(layer "F.SilkS")
			(hide yes)
			(effects
				(font
					(size 1.27 1.27)
				)
			)
		)
		(property "Value" ""
			(at 0 0 0)
			(layer "F.Fab")
			(effects
				(font
					(size 1.27 1.27)
				)
			)
		)
		(duplicate_pad_numbers_are_jumpers no)
		(fp_line
			(start -0.7874 -0.4064)
			(end 0.7874 -0.4064)
			(stroke
				(width 0.1524)
				(type default)
			)
			(layer "F.SilkS")
		)
		(fp_line
			(start -0.7874 0.4064)
			(end -0.7874 -0.4064)
			(stroke
				(width 0.1524)
				(type default)
			)
			(layer "F.SilkS")
		)
		(fp_line
			(start 0.7874 -0.4064)
			(end 0.7874 0.4064)
			(stroke
				(width 0.1524)
				(type default)
			)
			(layer "F.SilkS")
		)
		(fp_line
			(start 0.7874 0.4064)
			(end -0.7874 0.4064)
			(stroke
				(width 0.1524)
				(type default)
			)
			(layer "F.SilkS")
		)
		(fp_line
			(start -0.67945 -0.305054)
			(end -0.12065 -0.305054)
			(stroke
				(width 0.1)
				(type default)
			)
			(layer "F.Fab")
		)
		(fp_line
			(start -0.67945 0.3048)
			(end -0.67945 -0.305054)
			(stroke
				(width 0.1)
				(type default)
			)
			(layer "F.Fab")
		)
		(fp_line
			(start -0.12065 -0.305054)
			(end -0.12065 -0.2794)
			(stroke
				(width 0.1)
				(type default)
			)
			(layer "F.Fab")
		)
		(fp_line
			(start -0.12065 -0.2794)
			(end 0.12065 -0.2794)
			(stroke
				(width 0.1)
				(type default)
			)
			(layer "F.Fab")
		)
		(fp_line
			(start -0.12065 0.2794)
			(end -0.12065 0.3048)
			(stroke
				(width 0.1)
				(type default)
			)
			(layer "F.Fab")
		)
		(fp_line
			(start -0.12065 0.3048)
			(end -0.67945 0.3048)
			(stroke
				(width 0.1)
				(type default)
			)
			(layer "F.Fab")
		)
		(fp_line
			(start 0.120396 0.2794)
			(end -0.12065 0.2794)
			(stroke
				(width 0.1)
				(type default)
			)
			(layer "F.Fab")
		)
		(fp_line
			(start 0.120396 0.3048)
			(end 0.120396 0.2794)
			(stroke
				(width 0.1)
				(type default)
			)
			(layer "F.Fab")
		)
		(fp_line
			(start 0.12065 -0.3048)
			(end 0.67945 -0.3048)
			(stroke
				(width 0.1)
				(type default)
			)
			(layer "F.Fab")
		)
		(fp_line
			(start 0.12065 -0.2794)
			(end 0.12065 -0.3048)
			(stroke
				(width 0.1)
				(type default)
			)
			(layer "F.Fab")
		)
		(fp_line
			(start 0.67945 -0.3048)
			(end 0.67945 0.3048)
			(stroke
				(width 0.1)
				(type default)
			)
			(layer "F.Fab")
		)
		(fp_line
			(start 0.67945 0.3048)
			(end 0.120396 0.3048)
			(stroke
				(width 0.1)
				(type default)
			)
			(layer "F.Fab")
		)
		(pad "1" smd circle
			(at -0.40005 0)
			(size 0 0)
			(layers "F.Cu" "F.Mask" "F.Paste")
			(net "SPI_BMC_IO0_FLASH_R")
		)
		(pad "2" smd circle
			(at 0.40005 0)
			(size 0 0)
			(layers "F.Cu" "F.Mask" "F.Paste")
			(net "SPI_BMC_BOOT_MOSI")
		)
	)
	(footprint ""
		(layer "F.Cu")
		(at 35.1536 -88.4682 180)
		(property "Reference" "R492"
			(at 0 0 180)
			(layer "F.SilkS")
			(hide yes)
			(effects
				(font
					(size 1.27 1.27)
				)
			)
		)
		(property "Value" ""
			(at 0 0 180)
			(layer "F.Fab")
			(effects
				(font
					(size 1.27 1.27)
				)
			)
		)
		(duplicate_pad_numbers_are_jumpers no)
		(fp_line
			(start 0.7874 0.4064)
			(end -0.7874 0.4064)
			(stroke
				(width 0.1524)
				(type default)
			)
			(layer "F.SilkS")
		)
		(fp_line
			(start 0.7874 -0.4064)
			(end 0.7874 0.4064)
			(stroke
				(width 0.1524)
				(type default)
			)
			(layer "F.SilkS")
		)
		(fp_line
			(start -0.7874 0.4064)
			(end -0.7874 -0.4064)
			(stroke
				(width 0.1524)
				(type default)
			)
			(layer "F.SilkS")
		)
		(fp_line
			(start -0.7874 -0.4064)
			(end 0.7874 -0.4064)
			(stroke
				(width 0.1524)
				(type default)
			)
			(layer "F.SilkS")
		)
		(fp_line
			(start 0.67945 0.3048)
			(end 0.120396 0.3048)
			(stroke
				(width 0.1)
				(type default)
			)
			(layer "F.Fab")
		)
		(fp_line
			(start 0.67945 -0.3048)
			(end 0.67945 0.3048)
			(stroke
				(width 0.1)
				(type default)
			)
			(layer "F.Fab")
		)
		(fp_line
			(start 0.12065 -0.2794)
			(end 0.12065 -0.3048)
			(stroke
				(width 0.1)
				(type default)
			)
			(layer "F.Fab")
		)
		(fp_line
			(start 0.12065 -0.3048)
			(end 0.67945 -0.3048)
			(stroke
				(width 0.1)
				(type default)
			)
			(layer "F.Fab")
		)
		(fp_line
			(start 0.120396 0.3048)
			(end 0.120396 0.2794)
			(stroke
				(width 0.1)
				(type default)
			)
			(layer "F.Fab")
		)
		(fp_line
			(start 0.120396 0.2794)
			(end -0.12065 0.2794)
			(stroke
				(width 0.1)
				(type default)
			)
			(layer "F.Fab")
		)
		(fp_line
			(start -0.12065 0.3048)
			(end -0.67945 0.3048)
			(stroke
				(width 0.1)
				(type default)
			)
			(layer "F.Fab")
		)
		(fp_line
			(start -0.12065 0.2794)
			(end -0.12065 0.3048)
			(stroke
				(width 0.1)
				(type default)
			)
			(layer "F.Fab")
		)
		(fp_line
			(start -0.12065 -0.2794)
			(end 0.12065 -0.2794)
			(stroke
				(width 0.1)
				(type default)
			)
			(layer "F.Fab")
		)
		(fp_line
			(start -0.12065 -0.305054)
			(end -0.12065 -0.2794)
			(stroke
				(width 0.1)
				(type default)
			)
			(layer "F.Fab")
		)
		(fp_line
			(start -0.67945 0.3048)
			(end -0.67945 -0.305054)
			(stroke
				(width 0.1)
				(type default)
			)
			(layer "F.Fab")
		)
		(fp_line
			(start -0.67945 -0.305054)
			(end -0.12065 -0.305054)
			(stroke
				(width 0.1)
				(type default)
			)
			(layer "F.Fab")
		)
		(pad "1" smd circle
			(at -0.40005 0 180)
			(size 0 0)
			(layers "F.Cu" "F.Mask" "F.Paste")
			(net "P3V3_AUX")
		)
		(pad "2" smd circle
			(at 0.40005 0 180)
			(size 0 0)
			(layers "F.Cu" "F.Mask" "F.Paste")
			(net "SPI_PCH_IO3_FLASH_R1")
		)
	)
	(footprint ""
		(layer "F.Cu")
		(at 26.543 -102.743 -90)
		(property "Reference" "R635"
			(at 0 0 270)
			(layer "F.SilkS")
			(hide yes)
			(effects
				(font
					(size 1.27 1.27)
				)
			)
		)
		(property "Value" ""
			(at 0 0 270)
			(layer "F.Fab")
			(effects
				(font
					(size 1.27 1.27)
				)
			)
		)
		(duplicate_pad_numbers_are_jumpers no)
		(fp_line
			(start -0.7874 0.4064)
			(end -0.7874 -0.4064)
			(stroke
				(width 0.1524)
				(type default)
			)
			(layer "F.SilkS")
		)
		(fp_line
			(start 0.7874 0.4064)
			(end -0.7874 0.4064)
			(stroke
				(width 0.1524)
				(type default)
			)
			(layer "F.SilkS")
		)
		(fp_line
			(start -0.7874 -0.4064)
			(end 0.7874 -0.4064)
			(stroke
				(width 0.1524)
				(type default)
			)
			(layer "F.SilkS")
		)
		(fp_line
			(start 0.7874 -0.4064)
			(end 0.7874 0.4064)
			(stroke
				(width 0.1524)
				(type default)
			)
			(layer "F.SilkS")
		)
		(fp_line
			(start -0.67945 0.3048)
			(end -0.67945 -0.305054)
			(stroke
				(width 0.1)
				(type default)
			)
			(layer "F.Fab")
		)
		(fp_line
			(start -0.12065 0.3048)
			(end -0.67945 0.3048)
			(stroke
				(width 0.1)
				(type default)
			)
			(layer "F.Fab")
		)
		(fp_line
			(start 0.120396 0.3048)
			(end 0.120396 0.2794)
			(stroke
				(width 0.1)
				(type default)
			)
			(layer "F.Fab")
		)
		(fp_line
			(start 0.67945 0.3048)
			(end 0.120396 0.3048)
			(stroke
				(width 0.1)
				(type default)
			)
			(layer "F.Fab")
		)
		(fp_line
			(start -0.12065 0.2794)
			(end -0.12065 0.3048)
			(stroke
				(width 0.1)
				(type default)
			)
			(layer "F.Fab")
		)
		(fp_line
			(start 0.120396 0.2794)
			(end -0.12065 0.2794)
			(stroke
				(width 0.1)
				(type default)
			)
			(layer "F.Fab")
		)
		(fp_line
			(start -0.12065 -0.2794)
			(end 0.12065 -0.2794)
			(stroke
				(width 0.1)
				(type default)
			)
			(layer "F.Fab")
		)
		(fp_line
			(start 0.12065 -0.2794)
			(end 0.12065 -0.3048)
			(stroke
				(width 0.1)
				(type default)
			)
			(layer "F.Fab")
		)
		(fp_line
			(start 0.12065 -0.3048)
			(end 0.67945 -0.3048)
			(stroke
				(width 0.1)
				(type default)
			)
			(layer "F.Fab")
		)
		(fp_line
			(start 0.67945 -0.3048)
			(end 0.67945 0.3048)
			(stroke
				(width 0.1)
				(type default)
			)
			(layer "F.Fab")
		)
		(fp_line
			(start -0.67945 -0.305054)
			(end -0.12065 -0.305054)
			(stroke
				(width 0.1)
				(type default)
			)
			(layer "F.Fab")
		)
		(fp_line
			(start -0.12065 -0.305054)
			(end -0.12065 -0.2794)
			(stroke
				(width 0.1)
				(type default)
			)
			(layer "F.Fab")
		)
		(pad "1" smd circle
			(at -0.40005 0 270)
			(size 0 0)
			(layers "F.Cu" "F.Mask" "F.Paste")
			(net "RST_WDTRST_PLD_N")
		)
		(pad "2" smd circle
			(at 0.40005 0 270)
			(size 0 0)
			(layers "F.Cu" "F.Mask" "F.Paste")
			(net "RST_WDTRST_PLD_R2_N")
		)
	)
	(footprint ""
		(layer "F.Cu")
		(at 48.768 -34.6456 -90)
		(property "Reference" "R133"
			(at 0 0 270)
			(layer "F.SilkS")
			(hide yes)
			(effects
				(font
					(size 1.27 1.27)
				)
			)
		)
		(property "Value" ""
			(at 0 0 270)
			(layer "F.Fab")
			(effects
				(font
					(size 1.27 1.27)
				)
			)
		)
		(duplicate_pad_numbers_are_jumpers no)
		(fp_line
			(start -0.7874 0.4064)
			(end -0.7874 -0.4064)
			(stroke
				(width 0.1524)
				(type default)
			)
			(layer "F.SilkS")
		)
		(fp_line
			(start 0.7874 0.4064)
			(end -0.7874 0.4064)
			(stroke
				(width 0.1524)
				(type default)
			)
			(layer "F.SilkS")
		)
		(fp_line
			(start -0.7874 -0.4064)
			(end 0.7874 -0.4064)
			(stroke
				(width 0.1524)
				(type default)
			)
			(layer "F.SilkS")
		)
		(fp_line
			(start 0.7874 -0.4064)
			(end 0.7874 0.4064)
			(stroke
				(width 0.1524)
				(type default)
			)
			(layer "F.SilkS")
		)
		(fp_line
			(start -0.67945 0.3048)
			(end -0.67945 -0.305054)
			(stroke
				(width 0.1)
				(type default)
			)
			(layer "F.Fab")
		)
		(fp_line
			(start -0.12065 0.3048)
			(end -0.67945 0.3048)
			(stroke
				(width 0.1)
				(type default)
			)
			(layer "F.Fab")
		)
		(fp_line
			(start 0.120396 0.3048)
			(end 0.120396 0.2794)
			(stroke
				(width 0.1)
				(type default)
			)
			(layer "F.Fab")
		)
		(fp_line
			(start 0.67945 0.3048)
			(end 0.120396 0.3048)
			(stroke
				(width 0.1)
				(type default)
			)
			(layer "F.Fab")
		)
		(fp_line
			(start -0.12065 0.2794)
			(end -0.12065 0.3048)
			(stroke
				(width 0.1)
				(type default)
			)
			(layer "F.Fab")
		)
		(fp_line
			(start 0.120396 0.2794)
			(end -0.12065 0.2794)
			(stroke
				(width 0.1)
				(type default)
			)
			(layer "F.Fab")
		)
		(fp_line
			(start -0.12065 -0.2794)
			(end 0.12065 -0.2794)
			(stroke
				(width 0.1)
				(type default)
			)
			(layer "F.Fab")
		)
		(fp_line
			(start 0.12065 -0.2794)
			(end 0.12065 -0.3048)
			(stroke
				(width 0.1)
				(type default)
			)
			(layer "F.Fab")
		)
		(fp_line
			(start 0.12065 -0.3048)
			(end 0.67945 -0.3048)
			(stroke
				(width 0.1)
				(type default)
			)
			(layer "F.Fab")
		)
		(fp_line
			(start 0.67945 -0.3048)
			(end 0.67945 0.3048)
			(stroke
				(width 0.1)
				(type default)
			)
			(layer "F.Fab")
		)
		(fp_line
			(start -0.67945 -0.305054)
			(end -0.12065 -0.305054)
			(stroke
				(width 0.1)
				(type default)
			)
			(layer "F.Fab")
		)
		(fp_line
			(start -0.12065 -0.305054)
			(end -0.12065 -0.2794)
			(stroke
				(width 0.1)
				(type default)
			)
			(layer "F.Fab")
		)
		(pad "1" smd circle
			(at -0.40005 0 270)
			(size 0 0)
			(layers "F.Cu" "F.Mask" "F.Paste")
			(net "SMB_BMC_MM1_R_SDA")
		)
		(pad "2" smd circle
			(at 0.40005 0 270)
			(size 0 0)
			(layers "F.Cu" "F.Mask" "F.Paste")
			(net "SMB_BMC_MM1_SDA")
		)
	)
	(footprint ""
		(layer "F.Cu")
		(at 35.941 -36.068 90)
		(property "Reference" "C53"
			(at 0 0 90)
			(layer "F.SilkS")
			(hide yes)
			(effects
				(font
					(size 1.27 1.27)
				)
			)
		)
		(property "Value" ""
			(at 0 0 90)
			(layer "F.Fab")
			(effects
				(font
					(size 1.27 1.27)
				)
			)
		)
		(duplicate_pad_numbers_are_jumpers no)
		(fp_line
			(start 0.7874 -0.4064)
			(end 0.7874 0.4064)
			(stroke
				(width 0.1524)
				(type default)
			)
			(layer "F.SilkS")
		)
		(fp_line
			(start -0.7874 -0.4064)
			(end 0.7874 -0.4064)
			(stroke
				(width 0.1524)
				(type default)
			)
			(layer "F.SilkS")
		)
		(fp_line
			(start 0.7874 0.4064)
			(end -0.7874 0.4064)
			(stroke
				(width 0.1524)
				(type default)
			)
			(layer "F.SilkS")
		)
		(fp_line
			(start -0.7874 0.4064)
			(end -0.7874 -0.4064)
			(stroke
				(width 0.1524)
				(type default)
			)
			(layer "F.SilkS")
		)
		(fp_line
			(start -0.12065 -0.305054)
			(end -0.12065 -0.2794)
			(stroke
				(width 0.1)
				(type default)
			)
			(layer "F.Fab")
		)
		(fp_line
			(start -0.67945 -0.305054)
			(end -0.12065 -0.305054)
			(stroke
				(width 0.1)
				(type default)
			)
			(layer "F.Fab")
		)
		(fp_line
			(start 0.67945 -0.3048)
			(end 0.67945 0.3048)
			(stroke
				(width 0.1)
				(type default)
			)
			(layer "F.Fab")
		)
		(fp_line
			(start 0.12065 -0.3048)
			(end 0.67945 -0.3048)
			(stroke
				(width 0.1)
				(type default)
			)
			(layer "F.Fab")
		)
		(fp_line
			(start 0.12065 -0.2794)
			(end 0.12065 -0.3048)
			(stroke
				(width 0.1)
				(type default)
			)
			(layer "F.Fab")
		)
		(fp_line
			(start -0.12065 -0.2794)
			(end 0.12065 -0.2794)
			(stroke
				(width 0.1)
				(type default)
			)
			(layer "F.Fab")
		)
		(fp_line
			(start 0.120396 0.2794)
			(end -0.12065 0.2794)
			(stroke
				(width 0.1)
				(type default)
			)
			(layer "F.Fab")
		)
		(fp_line
			(start -0.12065 0.2794)
			(end -0.12065 0.3048)
			(stroke
				(width 0.1)
				(type default)
			)
			(layer "F.Fab")
		)
		(fp_line
			(start 0.67945 0.3048)
			(end 0.120396 0.3048)
			(stroke
				(width 0.1)
				(type default)
			)
			(layer "F.Fab")
		)
		(fp_line
			(start 0.120396 0.3048)
			(end 0.120396 0.2794)
			(stroke
				(width 0.1)
				(type default)
			)
			(layer "F.Fab")
		)
		(fp_line
			(start -0.12065 0.3048)
			(end -0.67945 0.3048)
			(stroke
				(width 0.1)
				(type default)
			)
			(layer "F.Fab")
		)
		(fp_line
			(start -0.67945 0.3048)
			(end -0.67945 -0.305054)
			(stroke
				(width 0.1)
				(type default)
			)
			(layer "F.Fab")
		)
		(pad "1" smd circle
			(at -0.40005 0 90)
			(size 0 0)
			(layers "F.Cu" "F.Mask" "F.Paste")
			(net "P3V3_P1V8_I2C_I3C")
		)
		(pad "2" smd circle
			(at 0.40005 0 90)
			(size 0 0)
			(layers "F.Cu" "F.Mask" "F.Paste")
			(net "GND")
		)
	)
	(footprint ""
		(layer "F.Cu")
		(at 46.9646 -77.2668)
		(property "Reference" "R548"
			(at 0 0 0)
			(layer "F.SilkS")
			(hide yes)
			(effects
				(font
					(size 1.27 1.27)
				)
			)
		)
		(property "Value" ""
			(at 0 0 0)
			(layer "F.Fab")
			(effects
				(font
					(size 1.27 1.27)
				)
			)
		)
		(duplicate_pad_numbers_are_jumpers no)
		(fp_line
			(start -0.7874 -0.4064)
			(end 0.7874 -0.4064)
			(stroke
				(width 0.1524)
				(type default)
			)
			(layer "F.SilkS")
		)
		(fp_line
			(start -0.7874 0.4064)
			(end -0.7874 -0.4064)
			(stroke
				(width 0.1524)
				(type default)
			)
			(layer "F.SilkS")
		)
		(fp_line
			(start 0.7874 -0.4064)
			(end 0.7874 0.4064)
			(stroke
				(width 0.1524)
				(type default)
			)
			(layer "F.SilkS")
		)
		(fp_line
			(start 0.7874 0.4064)
			(end -0.7874 0.4064)
			(stroke
				(width 0.1524)
				(type default)
			)
			(layer "F.SilkS")
		)
		(fp_line
			(start -0.67945 -0.305054)
			(end -0.12065 -0.305054)
			(stroke
				(width 0.1)
				(type default)
			)
			(layer "F.Fab")
		)
		(fp_line
			(start -0.67945 0.3048)
			(end -0.67945 -0.305054)
			(stroke
				(width 0.1)
				(type default)
			)
			(layer "F.Fab")
		)
		(fp_line
			(start -0.12065 -0.305054)
			(end -0.12065 -0.2794)
			(stroke
				(width 0.1)
				(type default)
			)
			(layer "F.Fab")
		)
		(fp_line
			(start -0.12065 -0.2794)
			(end 0.12065 -0.2794)
			(stroke
				(width 0.1)
				(type default)
			)
			(layer "F.Fab")
		)
		(fp_line
			(start -0.12065 0.2794)
			(end -0.12065 0.3048)
			(stroke
				(width 0.1)
				(type default)
			)
			(layer "F.Fab")
		)
		(fp_line
			(start -0.12065 0.3048)
			(end -0.67945 0.3048)
			(stroke
				(width 0.1)
				(type default)
			)
			(layer "F.Fab")
		)
		(fp_line
			(start 0.120396 0.2794)
			(end -0.12065 0.2794)
			(stroke
				(width 0.1)
				(type default)
			)
			(layer "F.Fab")
		)
		(fp_line
			(start 0.120396 0.3048)
			(end 0.120396 0.2794)
			(stroke
				(width 0.1)
				(type default)
			)
			(layer "F.Fab")
		)
		(fp_line
			(start 0.12065 -0.3048)
			(end 0.67945 -0.3048)
			(stroke
				(width 0.1)
				(type default)
			)
			(layer "F.Fab")
		)
		(fp_line
			(start 0.12065 -0.2794)
			(end 0.12065 -0.3048)
			(stroke
				(width 0.1)
				(type default)
			)
			(layer "F.Fab")
		)
		(fp_line
			(start 0.67945 -0.3048)
			(end 0.67945 0.3048)
			(stroke
				(width 0.1)
				(type default)
			)
			(layer "F.Fab")
		)
		(fp_line
			(start 0.67945 0.3048)
			(end 0.120396 0.3048)
			(stroke
				(width 0.1)
				(type default)
			)
			(layer "F.Fab")
		)
		(pad "1" smd circle
			(at -0.40005 0)
			(size 0 0)
			(layers "F.Cu" "F.Mask" "F.Paste")
			(net "BMC_RSTIND_N")
		)
		(pad "2" smd circle
			(at 0.40005 0)
			(size 0 0)
			(layers "F.Cu" "F.Mask" "F.Paste")
			(net "RD_N")
		)
	)
)
